(kicad_pcb
	(version 20260206)
	(generator "pcbnew")
	(generator_version "10.0")
	(general
		(thickness 1.6)
		(legacy_teardrops no)
	)
	(paper "A4")
	(title_block
		(title "Bryce Canyon_F.DPB_16315-1-OCP.brd")
		(comment 1 "Bryce Canyon / footprints 994-1001 of 2223")
	)
	(layers
		(0 "F.Cu" signal "TOP")
		(4 "In1.Cu" signal "L2GND")
		(6 "In2.Cu" signal "L3")
		(8 "In3.Cu" signal "L4GND")
		(10 "In4.Cu" signal "L5")
		(12 "In5.Cu" signal "L6VCC")
		(14 "In6.Cu" signal "L7VCC")
		(16 "In7.Cu" signal "L8")
		(18 "In8.Cu" signal "L9GND")
		(20 "In9.Cu" signal "L10")
		(22 "In10.Cu" signal "L11GND")
		(2 "B.Cu" signal "BOTTOM")
		(9 "F.Adhes" user "F.Adhesive")
		(11 "B.Adhes" user "B.Adhesive")
		(13 "F.Paste" user "Package Geometry/Pastemask Top")
		(15 "B.Paste" user "Package Geometry/Pastemask Bottom")
		(5 "F.SilkS" user "Ref Des/Silkscreen Top")
		(7 "B.SilkS" user "Ref Des/Silkscreen Bottom")
		(1 "F.Mask" user "Board Geometry/Soldermask Top")
		(3 "B.Mask" user "Board Geometry/Soldermask Bottom")
		(17 "Dwgs.User" user "User.Drawings")
		(19 "Cmts.User" user "User.Comments")
		(21 "Eco1.User" user "User.Eco1")
		(23 "Eco2.User" user "User.Eco2")
		(25 "Edge.Cuts" user "Board Geometry/Outline")
		(27 "Margin" user)
		(31 "F.CrtYd" user "Package Geometry/Place Bound Top")
		(29 "B.CrtYd" user "Package Geometry/Place Bound Bottom")
		(35 "F.Fab" user "Ref Des/Assembly Top")
		(33 "B.Fab" user "Ref Des/Assembly Bottom")
	)
	(footprint ""
		(layer "F.Cu")
		(at 96.324928 -92.799916)
		(property "Reference" ""
			(at 0 0 0)
			(layer "F.SilkS")
			(hide yes)
			(effects
				(font
					(size 1.27 1.27)
				)
			)
		)
		(property "Value" "*"
			(at -8.398764 -8.057642 0)
			(unlocked yes)
			(layer "F.Fab")
			(hide yes)
			(effects
				(font
					(size 1.016 1.016)
					(thickness 0.1524)
				)
			)
		)
		(duplicate_pad_numbers_are_jumpers no)
		(fp_poly
			(pts
				(arc
					(start 7.3152 0)
					(mid 0 7.3152)
					(end -7.3152 0)
				)
				(arc
					(start -7.3152 -5.9944)
					(mid 0 -13.3096)
					(end 7.3152 -5.9944)
				)
			)
			(stroke
				(width 0)
				(type default)
			)
			(fill no)
			(layer "B.CrtYd")
		)
		(fp_poly
			(pts
				(arc
					(start 7.3152 0)
					(mid 0 7.3152)
					(end -7.3152 0)
				)
				(arc
					(start -7.3152 -5.9944)
					(mid 0 -13.3096)
					(end 7.3152 -5.9944)
				)
			)
			(stroke
				(width 0)
				(type default)
			)
			(fill no)
			(layer "F.CrtYd")
		)
		(fp_poly
			(pts
				(arc
					(start 7.3152 0)
					(mid 0 7.3152)
					(end -7.3152 0)
				)
				(arc
					(start -7.3152 -5.9944)
					(mid 0 -13.3096)
					(end 7.3152 -5.9944)
				)
			)
			(stroke
				(width 0)
				(type default)
			)
			(fill no)
			(layer "B.Fab")
		)
		(fp_poly
			(pts
				(arc
					(start 7.3152 0)
					(mid 0 7.3152)
					(end -7.3152 0)
				)
				(arc
					(start -7.3152 -5.9944)
					(mid 0 -13.3096)
					(end 7.3152 -5.9944)
				)
			)
			(stroke
				(width 0)
				(type default)
			)
			(fill no)
			(layer "F.Fab")
		)
		(pad "1" thru_hole oval
			(at 0 0)
			(size 14.0208 20.0152)
			(drill 0.0254
				(offset 0 -2.9972)
			)
			(layers "*.Cu" "*.Mask")
			(remove_unused_layers no)
			(net "Net_27")
			(clearance -1.002284)
			(thermal_gap 0.1524)
			(padstack
				(mode front_inner_back)
				(layer "Inner"
					(shape custom)
					(size 2.928012 2.928012)
					(options
						(anchor circle)
					)
					(primitives
						(gr_poly
							(pts
								(arc
									(start 4.571746 -2.084324)
									(mid 0.000333 7.430372)
									(end -4.571492 -2.084324)
								)
								(arc
									(start -4.571492 -2.084324)
									(mid -3.570296 -3.611977)
									(end -2.875026 -5.30098)
								)
								(arc
									(start -2.875026 -5.30098)
									(mid 0.000217 -7.43089)
									(end 2.87528 -5.30098)
								)
								(arc
									(start 2.87528 -5.30098)
									(mid 3.570511 -3.611956)
									(end 4.571746 -2.084324)
								)
							)
							(width 0)
							(fill yes)
						)
					)
					(clearance 0.1524)
				)
				(layer "B.Cu"
					(shape oval)
					(size 14.0208 20.0152)
					(offset 0 -2.9972)
					(clearance -1.002284)
				)
			)
		)
		(zone
			(layers "F.Cu" "B.Cu" "In1.Cu" "In2.Cu" "In3.Cu" "In4.Cu" "In5.Cu" "In6.Cu"
				"In7.Cu" "In8.Cu" "In9.Cu" "In10.Cu"
			)
			(hatch none 0.5)
			(connect_pads
				(clearance 0)
			)
			(min_thickness 0.25)
			(keepout
				(tracks not_allowed)
				(vias allowed)
				(pads allowed)
				(copperpour not_allowed)
				(footprints allowed)
			)
			(placement
				(enabled no)
				(sheetname "")
			)
			(fill
				(thermal_gap 0.5)
				(thermal_bridge_width 0.5)
				(island_removal_mode 0)
			)
			(polygon
				(pts
					(arc
						(start 89.314528 -98.794316)
						(mid 96.324928 -105.804716)
						(end 103.335328 -98.794316)
					)
					(arc
						(start 103.335328 -92.799916)
						(mid 96.324928 -85.789516)
						(end 89.314528 -92.799916)
					)
				)
			)
		)
	)
	(footprint ""
		(layer "F.Cu")
		(at 221.697042 -206.90332 90)
		(property "Reference" "R409"
			(at 0 0 90)
			(layer "F.SilkS")
			(hide yes)
			(effects
				(font
					(size 1.27 1.27)
				)
			)
		)
		(property "Value" "10KR2F-2-GP"
			(at 0.064008 -3.993896 90)
			(unlocked yes)
			(layer "F.Fab")
			(hide yes)
			(effects
				(font
					(size 1.016 1.016)
					(thickness 0.1524)
				)
			)
		)
		(property "Device Type" "R402H16"
			(at 0.064008 -5.517896 90)
			(unlocked yes)
			(layer "F.Fab")
			(hide yes)
			(effects
				(font
					(size 1.016 1.016)
					(thickness 0.1524)
				)
			)
		)
		(duplicate_pad_numbers_are_jumpers no)
		(fp_line
			(start 0.508 -0.9398)
			(end -0.508 -0.9398)
			(stroke
				(width 0.1524)
				(type default)
			)
			(layer "F.SilkS")
		)
		(fp_line
			(start -0.508 -0.9398)
			(end -0.508 0.9398)
			(stroke
				(width 0.1524)
				(type default)
			)
			(layer "F.SilkS")
		)
		(fp_rect
			(start -0.508 0.9398)
			(end 0.508 -0.9398)
			(stroke
				(width 0)
				(type default)
			)
			(fill no)
			(layer "F.CrtYd")
		)
		(fp_rect
			(start -0.508 0.9398)
			(end 0.508 -0.9398)
			(stroke
				(width 0)
				(type default)
			)
			(fill no)
			(layer "F.Fab")
		)
		(pad "1" smd custom
			(at 0 -0.4445 90)
			(size 0.1397 0.1397)
			(layers "F.Cu" "F.Mask" "F.Paste")
			(net "P3V3_STBY_A")
			(options
				(clearance outline)
				(anchor circle)
			)
			(primitives
				(gr_poly
					(pts
						(arc
							(start -0.1778 -0.2794)
							(mid -0.249642 -0.249642)
							(end -0.2794 -0.1778)
						)
						(arc
							(start -0.2794 0.1778)
							(mid -0.249642 0.249642)
							(end -0.1778 0.2794)
						)
						(arc
							(start 0.1778 0.2794)
							(mid 0.249642 0.249642)
							(end 0.2794 0.1778)
						)
						(arc
							(start 0.2794 -0.1778)
							(mid 0.249642 -0.249642)
							(end 0.1778 -0.2794)
						)
					)
					(width 0)
					(fill yes)
				)
			)
		)
		(pad "2" smd custom
			(at 0 0.4445 90)
			(size 0.1397 0.1397)
			(layers "F.Cu" "F.Mask" "F.Paste")
			(net "I2C_SCC_BUFF_EN")
			(options
				(clearance outline)
				(anchor circle)
			)
			(primitives
				(gr_poly
					(pts
						(arc
							(start -0.1778 -0.2794)
							(mid -0.249642 -0.249642)
							(end -0.2794 -0.1778)
						)
						(arc
							(start -0.2794 0.1778)
							(mid -0.249642 0.249642)
							(end -0.1778 0.2794)
						)
						(arc
							(start 0.1778 0.2794)
							(mid 0.249642 0.249642)
							(end 0.2794 0.1778)
						)
						(arc
							(start 0.2794 -0.1778)
							(mid 0.249642 -0.249642)
							(end 0.1778 -0.2794)
						)
					)
					(width 0)
					(fill yes)
				)
			)
		)
	)
	(footprint ""
		(layer "F.Cu")
		(at 413.004 -298.704)
		(property "Reference" "TP47"
			(at 0 0 0)
			(layer "F.SilkS")
			(hide yes)
			(effects
				(font
					(size 1.27 1.27)
				)
			)
		)
		(property "Value" "TPAD32-GP"
			(at -0.0508 -1.6764 0)
			(unlocked yes)
			(layer "F.Fab")
			(hide yes)
			(effects
				(font
					(size 1.016 1.016)
					(thickness 0.1524)
				)
			)
		)
		(property "Device Type" "TPAD32"
			(at -0.0508 -3.2004 0)
			(unlocked yes)
			(layer "F.Fab")
			(hide yes)
			(effects
				(font
					(size 1.016 1.016)
					(thickness 0.1524)
				)
			)
		)
		(duplicate_pad_numbers_are_jumpers no)
		(fp_poly
			(pts
				(arc
					(start 0.4064 0)
					(mid -0.4064 0)
					(end 0.4064 0)
				)
			)
			(stroke
				(width 0)
				(type default)
			)
			(fill no)
			(layer "F.CrtYd")
		)
		(fp_poly
			(pts
				(arc
					(start 0.7112 0)
					(mid -0.7112 0)
					(end 0.7112 0)
				)
			)
			(stroke
				(width 0)
				(type default)
			)
			(fill no)
			(layer "F.Fab")
		)
		(pad "1" smd circle
			(at 0 0)
			(size 0.8128 0.8128)
			(layers "F.Cu" "F.Mask" "F.Paste")
			(net "ACT_HDD_9")
		)
	)
	(footprint ""
		(layer "F.Cu")
		(at 14.842998 -168.482518 -90)
		(property "Reference" "R421"
			(at 0 0 270)
			(layer "F.SilkS")
			(hide yes)
			(effects
				(font
					(size 1.27 1.27)
				)
			)
		)
		(property "Value" "300KR2F-GP"
			(at 0.064008 -3.993896 270)
			(unlocked yes)
			(layer "F.Fab")
			(hide yes)
			(effects
				(font
					(size 1.016 1.016)
					(thickness 0.1524)
				)
			)
		)
		(property "Device Type" "R402H16"
			(at 0.064008 -5.517896 270)
			(unlocked yes)
			(layer "F.Fab")
			(hide yes)
			(effects
				(font
					(size 1.016 1.016)
					(thickness 0.1524)
				)
			)
		)
		(duplicate_pad_numbers_are_jumpers no)
		(fp_line
			(start -0.508 -0.9398)
			(end -0.508 0.9398)
			(stroke
				(width 0.1524)
				(type default)
			)
			(layer "F.SilkS")
		)
		(fp_line
			(start 0.508 -0.9398)
			(end -0.508 -0.9398)
			(stroke
				(width 0.1524)
				(type default)
			)
			(layer "F.SilkS")
		)
		(fp_rect
			(start -0.508 0.9398)
			(end 0.508 -0.9398)
			(stroke
				(width 0)
				(type default)
			)
			(fill no)
			(layer "F.CrtYd")
		)
		(fp_rect
			(start -0.508 0.9398)
			(end 0.508 -0.9398)
			(stroke
				(width 0)
				(type default)
			)
			(fill no)
			(layer "F.Fab")
		)
		(pad "1" smd custom
			(at 0 -0.4445 270)
			(size 0.1397 0.1397)
			(layers "F.Cu" "F.Mask" "F.Paste")
			(net "SW_HDD_N12")
			(options
				(clearance outline)
				(anchor circle)
			)
			(primitives
				(gr_poly
					(pts
						(arc
							(start -0.1778 -0.2794)
							(mid -0.249642 -0.249642)
							(end -0.2794 -0.1778)
						)
						(arc
							(start -0.2794 0.1778)
							(mid -0.249642 0.249642)
							(end -0.1778 0.2794)
						)
						(arc
							(start 0.1778 0.2794)
							(mid 0.249642 0.249642)
							(end 0.2794 0.1778)
						)
						(arc
							(start 0.2794 -0.1778)
							(mid 0.249642 -0.249642)
							(end 0.1778 -0.2794)
						)
					)
					(width 0)
					(fill yes)
				)
			)
		)
		(pad "2" smd custom
			(at 0 0.4445 270)
			(size 0.1397 0.1397)
			(layers "F.Cu" "F.Mask" "F.Paste")
			(net "P12V_A")
			(options
				(clearance outline)
				(anchor circle)
			)
			(primitives
				(gr_poly
					(pts
						(arc
							(start -0.1778 -0.2794)
							(mid -0.249642 -0.249642)
							(end -0.2794 -0.1778)
						)
						(arc
							(start -0.2794 0.1778)
							(mid -0.249642 0.249642)
							(end -0.1778 0.2794)
						)
						(arc
							(start 0.1778 0.2794)
							(mid 0.249642 0.249642)
							(end 0.2794 0.1778)
						)
						(arc
							(start 0.2794 -0.1778)
							(mid 0.249642 -0.249642)
							(end 0.1778 -0.2794)
						)
					)
					(width 0)
					(fill yes)
				)
			)
		)
	)
	(footprint ""
		(layer "F.Cu")
		(at 67.347846 -61.127894 90)
		(property "Reference" "C371"
			(at 0 0 90)
			(layer "F.SilkS")
			(hide yes)
			(effects
				(font
					(size 1.27 1.27)
				)
			)
		)
		(property "Value" "SCD01U50V2KX-1GP"
			(at 1.1811 -2.7051 90)
			(unlocked yes)
			(layer "F.Fab")
			(hide yes)
			(effects
				(font
					(size 1.016 1.016)
					(thickness 0.1524)
				)
			)
		)
		(property "Device Type" "C402H22"
			(at 1.1811 -4.2291 90)
			(unlocked yes)
			(layer "F.Fab")
			(hide yes)
			(effects
				(font
					(size 1.016 1.016)
					(thickness 0.1524)
				)
			)
		)
		(duplicate_pad_numbers_are_jumpers no)
		(fp_rect
			(start -0.4318 0.9525)
			(end 0.4318 -0.9525)
			(stroke
				(width 0)
				(type default)
			)
			(fill no)
			(layer "F.CrtYd")
		)
		(fp_rect
			(start -0.4318 0.9525)
			(end 0.4318 -0.9525)
			(stroke
				(width 0)
				(type default)
			)
			(fill no)
			(layer "F.Fab")
		)
		(pad "1" smd custom
			(at 0 -0.4445 90)
			(size 0.1524 0.1524)
			(layers "F.Cu" "F.Mask" "F.Paste")
			(net "HDD_PRSNT_25")
			(options
				(clearance outline)
				(anchor circle)
			)
			(primitives
				(gr_poly
					(pts
						(arc
							(start 0.3048 -0.2032)
							(mid 0.275042 -0.275042)
							(end 0.2032 -0.3048)
						)
						(arc
							(start -0.2032 -0.3048)
							(mid -0.275042 -0.275042)
							(end -0.3048 -0.2032)
						)
						(arc
							(start -0.3048 0.2032)
							(mid -0.275042 0.275042)
							(end -0.2032 0.3048)
						)
						(arc
							(start 0.2032 0.3048)
							(mid 0.275042 0.275042)
							(end 0.3048 0.2032)
						)
					)
					(width 0)
					(fill yes)
				)
			)
		)
		(pad "2" smd custom
			(at 0 0.4445 90)
			(size 0.1524 0.1524)
			(layers "F.Cu" "F.Mask" "F.Paste")
			(net "GND")
			(options
				(clearance outline)
				(anchor circle)
			)
			(primitives
				(gr_poly
					(pts
						(arc
							(start 0.3048 -0.2032)
							(mid 0.275042 -0.275042)
							(end 0.2032 -0.3048)
						)
						(arc
							(start -0.2032 -0.3048)
							(mid -0.275042 -0.275042)
							(end -0.3048 -0.2032)
						)
						(arc
							(start -0.3048 0.2032)
							(mid -0.275042 0.275042)
							(end -0.2032 0.3048)
						)
						(arc
							(start 0.2032 0.3048)
							(mid 0.275042 0.275042)
							(end 0.3048 0.2032)
						)
					)
					(width 0)
					(fill yes)
				)
			)
		)
	)
	(footprint ""
		(layer "F.Cu")
		(at 237.998 -395.9098 180)
		(property "Reference" "C592"
			(at 0 0 180)
			(layer "F.SilkS")
			(hide yes)
			(effects
				(font
					(size 1.27 1.27)
				)
			)
		)
		(property "Value" "SCD1U25V2KX-2-GP"
			(at 1.1811 -2.7051 180)
			(unlocked yes)
			(layer "F.Fab")
			(hide yes)
			(effects
				(font
					(size 1.016 1.016)
					(thickness 0.1524)
				)
			)
		)
		(property "Device Type" "C402H22"
			(at 1.1811 -4.2291 180)
			(unlocked yes)
			(layer "F.Fab")
			(hide yes)
			(effects
				(font
					(size 1.016 1.016)
					(thickness 0.1524)
				)
			)
		)
		(duplicate_pad_numbers_are_jumpers no)
		(fp_rect
			(start -0.4318 0.9525)
			(end 0.4318 -0.9525)
			(stroke
				(width 0)
				(type default)
			)
			(fill no)
			(layer "F.CrtYd")
		)
		(fp_rect
			(start -0.4318 0.9525)
			(end 0.4318 -0.9525)
			(stroke
				(width 0)
				(type default)
			)
			(fill no)
			(layer "F.Fab")
		)
		(pad "1" smd custom
			(at 0 -0.4445 180)
			(size 0.1524 0.1524)
			(layers "F.Cu" "F.Mask" "F.Paste")
			(net "MB3_ISTART_R")
			(options
				(clearance outline)
				(anchor circle)
			)
			(primitives
				(gr_poly
					(pts
						(arc
							(start 0.3048 -0.2032)
							(mid 0.275042 -0.275042)
							(end 0.2032 -0.3048)
						)
						(arc
							(start -0.2032 -0.3048)
							(mid -0.275042 -0.275042)
							(end -0.3048 -0.2032)
						)
						(arc
							(start -0.3048 0.2032)
							(mid -0.275042 0.275042)
							(end -0.2032 0.3048)
						)
						(arc
							(start 0.2032 0.3048)
							(mid 0.275042 0.275042)
							(end 0.3048 0.2032)
						)
					)
					(width 0)
					(fill yes)
				)
			)
		)
		(pad "2" smd custom
			(at 0 0.4445 180)
			(size 0.1524 0.1524)
			(layers "F.Cu" "F.Mask" "F.Paste")
			(net "AGND_CURRENT_DPB")
			(options
				(clearance outline)
				(anchor circle)
			)
			(primitives
				(gr_poly
					(pts
						(arc
							(start 0.3048 -0.2032)
							(mid 0.275042 -0.275042)
							(end 0.2032 -0.3048)
						)
						(arc
							(start -0.2032 -0.3048)
							(mid -0.275042 -0.275042)
							(end -0.3048 -0.2032)
						)
						(arc
							(start -0.3048 0.2032)
							(mid -0.275042 0.275042)
							(end -0.2032 0.3048)
						)
						(arc
							(start 0.2032 0.3048)
							(mid 0.275042 0.275042)
							(end 0.3048 0.2032)
						)
					)
					(width 0)
					(fill yes)
				)
			)
		)
	)
	(footprint ""
		(layer "F.Cu")
		(at 32.463486 -159.219392 90)
		(property "Reference" "C194"
			(at 0 0 90)
			(layer "F.SilkS")
			(hide yes)
			(effects
				(font
					(size 1.27 1.27)
				)
			)
		)
		(property "Value" "SCD01U16V1KX-GP"
			(at -2.8321 -1.7399 90)
			(unlocked yes)
			(layer "F.Fab")
			(hide yes)
			(effects
				(font
					(size 1.016 1.016)
					(thickness 0.1524)
				)
			)
		)
		(property "Device Type" "C0201H13"
			(at -2.8321 -3.2639 90)
			(unlocked yes)
			(layer "F.Fab")
			(hide yes)
			(effects
				(font
					(size 1.016 1.016)
					(thickness 0.1524)
				)
			)
		)
		(duplicate_pad_numbers_are_jumpers no)
		(fp_rect
			(start -0.2794 0.6477)
			(end 0.2794 -0.6477)
			(stroke
				(width 0)
				(type default)
			)
			(fill no)
			(layer "F.CrtYd")
		)
		(fp_rect
			(start -0.2794 0.6477)
			(end 0.2794 -0.6477)
			(stroke
				(width 0)
				(type default)
			)
			(fill no)
			(layer "F.Fab")
		)
		(pad "1" smd custom
			(at 0 -0.2794 90)
			(size 0.0762 0.0762)
			(layers "F.Cu" "F.Mask" "F.Paste")
			(net "SAS_HDD_RX_N12")
			(options
				(clearance outline)
				(anchor circle)
			)
			(primitives
				(gr_poly
					(pts
						(arc
							(start 0.1524 -0.127)
							(mid 0.137521 -0.162921)
							(end 0.1016 -0.1778)
						)
						(arc
							(start -0.1016 -0.1778)
							(mid -0.137521 -0.162921)
							(end -0.1524 -0.127)
						)
						(arc
							(start -0.1524 0.127)
							(mid -0.137521 0.162921)
							(end -0.1016 0.1778)
						)
						(arc
							(start 0.1016 0.1778)
							(mid 0.137521 0.162921)
							(end 0.1524 0.127)
						)
					)
					(width 0)
					(fill yes)
				)
			)
		)
		(pad "2" smd custom
			(at 0 0.2794 90)
			(size 0.0762 0.0762)
			(layers "F.Cu" "F.Mask" "F.Paste")
			(net "PHY_SCC_A_TO_DRV_A_12_DN")
			(options
				(clearance outline)
				(anchor circle)
			)
			(primitives
				(gr_poly
					(pts
						(arc
							(start 0.1524 -0.127)
							(mid 0.137521 -0.162921)
							(end 0.1016 -0.1778)
						)
						(arc
							(start -0.1016 -0.1778)
							(mid -0.137521 -0.162921)
							(end -0.1524 -0.127)
						)
						(arc
							(start -0.1524 0.127)
							(mid -0.137521 0.162921)
							(end -0.1016 0.1778)
						)
						(arc
							(start 0.1016 0.1778)
							(mid 0.137521 0.162921)
							(end 0.1524 0.127)
						)
					)
					(width 0)
					(fill yes)
				)
			)
		)
	)
	(footprint ""
		(layer "F.Cu")
		(at 272.542 -314.505086 180)
		(property "Reference" "VIA59"
			(at 0 0 180)
			(layer "F.SilkS")
			(hide yes)
			(effects
				(font
					(size 1.27 1.27)
				)
			)
		)
		(property "Value" "100OHM-8L-1D6MM-L18L16-GP"
			(at -3.7211 -4.5085 180)
			(unlocked yes)
			(layer "F.Fab")
			(hide yes)
			(effects
				(font
					(size 1.016 1.016)
					(thickness 0.1524)
				)
			)
		)
		(property "Device Type" "VIA-PCIE-4P-394076"
			(at -3.7211 -6.0325 180)
			(unlocked yes)
			(layer "F.Fab")
			(hide yes)
			(effects
				(font
					(size 1.016 1.016)
					(thickness 0.1524)
				)
			)
		)
		(duplicate_pad_numbers_are_jumpers no)
		(fp_rect
			(start -1.9685 0.381)
			(end 1.9685 -0.381)
			(stroke
				(width 0)
				(type default)
			)
			(fill no)
			(layer "F.CrtYd")
		)
		(fp_rect
			(start -1.9685 0.381)
			(end 1.9685 -0.381)
			(stroke
				(width 0)
				(type default)
			)
			(fill no)
			(layer "F.Fab")
		)
		(pad "1" thru_hole circle
			(at -1.5875 0 180)
			(size 0.508 0.508)
			(drill 0.254)
			(layers "*.Cu" "*.Mask")
			(remove_unused_layers no)
			(net "GND")
			(clearance 0.127)
			(thermal_gap 0.127)
		)
		(pad "2" thru_hole circle
			(at -0.5715 0 180)
			(size 0.508 0.508)
			(drill 0.254)
			(layers "*.Cu" "*.Mask")
			(remove_unused_layers no)
			(net "PHY_SCC_A_TO_DRV_A_25_DP")
			(clearance 0.127)
			(thermal_gap 0.127)
		)
		(pad "3" thru_hole circle
			(at 0.5715 0 180)
			(size 0.508 0.508)
			(drill 0.254)
			(layers "*.Cu" "*.Mask")
			(remove_unused_layers no)
			(net "PHY_SCC_A_TO_DRV_A_25_DN")
			(clearance 0.127)
			(thermal_gap 0.127)
		)
		(pad "4" thru_hole circle
			(at 1.5875 0 180)
			(size 0.508 0.508)
			(drill 0.254)
			(layers "*.Cu" "*.Mask")
			(remove_unused_layers no)
			(net "GND")
			(clearance 0.127)
			(thermal_gap 0.127)
		)
	)
)
